(kicad_pcb
	(version 20260206)
	(generator "pcbnew")
	(generator_version "10.0")
	(general
		(thickness 1.6)
		(legacy_teardrops no)
	)
	(paper "A4")
	(title_block
		(title "peb — Lightning_PEB_BRD.brd")
		(comment 1 "Lightning (Wiwynn / Facebook NVMe JBOF) / footprints 2343-2349 of 2563")
	)
	(layers
		(0 "F.Cu" signal "TOP")
		(4 "In1.Cu" signal "L2GND")
		(6 "In2.Cu" signal "L3")
		(8 "In3.Cu" signal "L4VCC")
		(10 "In4.Cu" signal "L5VCC")
		(12 "In5.Cu" signal "L6")
		(14 "In6.Cu" signal "L7GND")
		(2 "B.Cu" signal "BOTTOM")
		(9 "F.Adhes" user "F.Adhesive")
		(11 "B.Adhes" user "B.Adhesive")
		(13 "F.Paste" user "Package Geometry/Pastemask Top")
		(15 "B.Paste" user "Package Geometry/Pastemask Bottom")
		(5 "F.SilkS" user "Ref Des/Silkscreen Top")
		(7 "B.SilkS" user "Ref Des/Silkscreen Bottom")
		(1 "F.Mask" user "Board Geometry/Soldermask Top")
		(3 "B.Mask" user "Board Geometry/Soldermask Bottom")
		(17 "Dwgs.User" user "User.Drawings")
		(19 "Cmts.User" user "User.Comments")
		(21 "Eco1.User" user "User.Eco1")
		(23 "Eco2.User" user "User.Eco2")
		(25 "Edge.Cuts" user "Board Geometry/Outline")
		(27 "Margin" user)
		(31 "F.CrtYd" user "Package Geometry/Place Bound Top")
		(29 "B.CrtYd" user "Package Geometry/Place Bound Bottom")
		(35 "F.Fab" user "Ref Des/Assembly Top")
		(33 "B.Fab" user "Ref Des/Assembly Bottom")
	)
	(footprint ""
		(layer "B.Cu")
		(at 53.721 -134.747 -90)
		(property "Reference" "R373"
			(at 0 0 90)
			(layer "B.SilkS")
			(hide yes)
			(effects
				(font
					(size 1.27 1.27)
				)
				(justify mirror)
			)
		)
		(property "Value" "0R2J-2-GP"
			(at -0.064008 -3.993896 270)
			(unlocked yes)
			(layer "B.Fab")
			(hide yes)
			(effects
				(font
					(size 1.016 1.016)
					(thickness 0.1524)
				)
				(justify mirror)
			)
		)
		(property "Device Type" "R402H16"
			(at -0.064008 -5.517896 270)
			(unlocked yes)
			(layer "B.Fab")
			(hide yes)
			(effects
				(font
					(size 1.016 1.016)
					(thickness 0.1524)
				)
				(justify mirror)
			)
		)
		(duplicate_pad_numbers_are_jumpers no)
		(fp_line
			(start -0.508 -0.9398)
			(end 0.508 -0.9398)
			(stroke
				(width 0.1524)
				(type default)
			)
			(layer "B.SilkS")
		)
		(fp_line
			(start 0.508 -0.9398)
			(end 0.508 0.9398)
			(stroke
				(width 0.1524)
				(type default)
			)
			(layer "B.SilkS")
		)
		(fp_rect
			(start 0.508 0.9398)
			(end -0.508 -0.9398)
			(stroke
				(width 0)
				(type default)
			)
			(fill no)
			(layer "B.CrtYd")
		)
		(fp_rect
			(start 0.508 0.9398)
			(end -0.508 -0.9398)
			(stroke
				(width 0)
				(type default)
			)
			(fill no)
			(layer "B.Fab")
		)
		(pad "1" smd custom
			(at 0 -0.4445 90)
			(size 0.1397 0.1397)
			(layers "B.Cu" "B.Mask" "B.Paste")
			(net "ADC_P1V26")
			(options
				(clearance outline)
				(anchor circle)
			)
			(primitives
				(gr_poly
					(pts
						(arc
							(start -0.1778 0.2794)
							(mid -0.249642 0.249642)
							(end -0.2794 0.1778)
						)
						(arc
							(start -0.2794 -0.1778)
							(mid -0.249642 -0.249642)
							(end -0.1778 -0.2794)
						)
						(arc
							(start 0.1778 -0.2794)
							(mid 0.249642 -0.249642)
							(end 0.2794 -0.1778)
						)
						(arc
							(start 0.2794 0.1778)
							(mid 0.249642 0.249642)
							(end 0.1778 0.2794)
						)
					)
					(width 0)
					(fill yes)
				)
			)
		)
		(pad "2" smd custom
			(at 0 0.4445 90)
			(size 0.1397 0.1397)
			(layers "B.Cu" "B.Mask" "B.Paste")
			(net "ADC_P1V26_BMC")
			(options
				(clearance outline)
				(anchor circle)
			)
			(primitives
				(gr_poly
					(pts
						(arc
							(start -0.1778 0.2794)
							(mid -0.249642 0.249642)
							(end -0.2794 0.1778)
						)
						(arc
							(start -0.2794 -0.1778)
							(mid -0.249642 -0.249642)
							(end -0.1778 -0.2794)
						)
						(arc
							(start 0.1778 -0.2794)
							(mid 0.249642 -0.249642)
							(end 0.2794 -0.1778)
						)
						(arc
							(start 0.2794 0.1778)
							(mid 0.249642 0.249642)
							(end 0.1778 0.2794)
						)
					)
					(width 0)
					(fill yes)
				)
			)
		)
	)
	(footprint ""
		(layer "B.Cu")
		(at 125.28423 -33.48355 180)
		(property "Reference" "C130"
			(at 0 0 0)
			(layer "B.SilkS")
			(hide yes)
			(effects
				(font
					(size 1.27 1.27)
				)
				(justify mirror)
			)
		)
		(property "Value" "SCD1U10V2KX-5GP"
			(at -1.1811 -2.7051 180)
			(unlocked yes)
			(layer "B.Fab")
			(hide yes)
			(effects
				(font
					(size 1.016 1.016)
					(thickness 0.1524)
				)
				(justify mirror)
			)
		)
		(property "Device Type" "C402H22"
			(at -1.1811 -4.2291 180)
			(unlocked yes)
			(layer "B.Fab")
			(hide yes)
			(effects
				(font
					(size 1.016 1.016)
					(thickness 0.1524)
				)
				(justify mirror)
			)
		)
		(duplicate_pad_numbers_are_jumpers no)
		(fp_rect
			(start 0.4318 0.9525)
			(end -0.4318 -0.9525)
			(stroke
				(width 0)
				(type default)
			)
			(fill no)
			(layer "B.CrtYd")
		)
		(fp_rect
			(start 0.4318 0.9525)
			(end -0.4318 -0.9525)
			(stroke
				(width 0)
				(type default)
			)
			(fill no)
			(layer "B.Fab")
		)
		(pad "1" smd custom
			(at 0 -0.4445)
			(size 0.1524 0.1524)
			(layers "B.Cu" "B.Mask" "B.Paste")
			(net "GND")
			(options
				(clearance outline)
				(anchor circle)
			)
			(primitives
				(gr_poly
					(pts
						(arc
							(start 0.3048 0.2032)
							(mid 0.275042 0.275042)
							(end 0.2032 0.3048)
						)
						(arc
							(start -0.2032 0.3048)
							(mid -0.275042 0.275042)
							(end -0.3048 0.2032)
						)
						(arc
							(start -0.3048 -0.2032)
							(mid -0.275042 -0.275042)
							(end -0.2032 -0.3048)
						)
						(arc
							(start 0.2032 -0.3048)
							(mid 0.275042 -0.275042)
							(end 0.3048 -0.2032)
						)
					)
					(width 0)
					(fill yes)
				)
			)
		)
		(pad "2" smd custom
			(at 0 0.4445)
			(size 0.1524 0.1524)
			(layers "B.Cu" "B.Mask" "B.Paste")
			(net "P3V3_STBY")
			(options
				(clearance outline)
				(anchor circle)
			)
			(primitives
				(gr_poly
					(pts
						(arc
							(start 0.3048 0.2032)
							(mid 0.275042 0.275042)
							(end 0.2032 0.3048)
						)
						(arc
							(start -0.2032 0.3048)
							(mid -0.275042 0.275042)
							(end -0.3048 0.2032)
						)
						(arc
							(start -0.3048 -0.2032)
							(mid -0.275042 -0.275042)
							(end -0.2032 -0.3048)
						)
						(arc
							(start 0.2032 -0.3048)
							(mid 0.275042 -0.275042)
							(end 0.3048 -0.2032)
						)
					)
					(width 0)
					(fill yes)
				)
			)
		)
	)
	(footprint ""
		(layer "B.Cu")
		(at 57.15 -132.08)
		(property "Reference" "R5770"
			(at 0 0 0)
			(layer "B.SilkS")
			(hide yes)
			(effects
				(font
					(size 1.27 1.27)
				)
				(justify mirror)
			)
		)
		(property "Value" "1KR2F-3-GP"
			(at -0.064008 -3.993896 0)
			(unlocked yes)
			(layer "B.Fab")
			(hide yes)
			(effects
				(font
					(size 1.016 1.016)
					(thickness 0.1524)
				)
				(justify mirror)
			)
		)
		(property "Device Type" "R402H16"
			(at -0.064008 -5.517896 0)
			(unlocked yes)
			(layer "B.Fab")
			(hide yes)
			(effects
				(font
					(size 1.016 1.016)
					(thickness 0.1524)
				)
				(justify mirror)
			)
		)
		(duplicate_pad_numbers_are_jumpers no)
		(fp_line
			(start -0.508 -0.9398)
			(end 0.508 -0.9398)
			(stroke
				(width 0.1524)
				(type default)
			)
			(layer "B.SilkS")
		)
		(fp_line
			(start 0.508 -0.9398)
			(end 0.508 0.9398)
			(stroke
				(width 0.1524)
				(type default)
			)
			(layer "B.SilkS")
		)
		(fp_rect
			(start 0.508 0.9398)
			(end -0.508 -0.9398)
			(stroke
				(width 0)
				(type default)
			)
			(fill no)
			(layer "B.CrtYd")
		)
		(fp_rect
			(start 0.508 0.9398)
			(end -0.508 -0.9398)
			(stroke
				(width 0)
				(type default)
			)
			(fill no)
			(layer "B.Fab")
		)
		(pad "1" smd custom
			(at 0 -0.4445 180)
			(size 0.1397 0.1397)
			(layers "B.Cu" "B.Mask" "B.Paste")
			(net "ADC_P3V3_STBY")
			(options
				(clearance outline)
				(anchor circle)
			)
			(primitives
				(gr_poly
					(pts
						(arc
							(start -0.1778 0.2794)
							(mid -0.249642 0.249642)
							(end -0.2794 0.1778)
						)
						(arc
							(start -0.2794 -0.1778)
							(mid -0.249642 -0.249642)
							(end -0.1778 -0.2794)
						)
						(arc
							(start 0.1778 -0.2794)
							(mid 0.249642 -0.249642)
							(end 0.2794 -0.1778)
						)
						(arc
							(start 0.2794 0.1778)
							(mid 0.249642 0.249642)
							(end 0.1778 0.2794)
						)
					)
					(width 0)
					(fill yes)
				)
			)
		)
		(pad "2" smd custom
			(at 0 0.4445 180)
			(size 0.1397 0.1397)
			(layers "B.Cu" "B.Mask" "B.Paste")
			(net "GND")
			(options
				(clearance outline)
				(anchor circle)
			)
			(primitives
				(gr_poly
					(pts
						(arc
							(start -0.1778 0.2794)
							(mid -0.249642 0.249642)
							(end -0.2794 0.1778)
						)
						(arc
							(start -0.2794 -0.1778)
							(mid -0.249642 -0.249642)
							(end -0.1778 -0.2794)
						)
						(arc
							(start 0.1778 -0.2794)
							(mid 0.249642 -0.249642)
							(end 0.2794 -0.1778)
						)
						(arc
							(start 0.2794 0.1778)
							(mid 0.249642 0.249642)
							(end 0.1778 0.2794)
						)
					)
					(width 0)
					(fill yes)
				)
			)
		)
	)
	(footprint ""
		(layer "B.Cu")
		(at 339.344 -178.689)
		(property "Reference" "R276"
			(at 0 0 0)
			(layer "B.SilkS")
			(hide yes)
			(effects
				(font
					(size 1.27 1.27)
				)
				(justify mirror)
			)
		)
		(property "Value" "4K7R2F-GP"
			(at -0.064008 -3.993896 0)
			(unlocked yes)
			(layer "B.Fab")
			(hide yes)
			(effects
				(font
					(size 1.016 1.016)
					(thickness 0.1524)
				)
				(justify mirror)
			)
		)
		(property "Device Type" "R402H16"
			(at -0.064008 -5.517896 0)
			(unlocked yes)
			(layer "B.Fab")
			(hide yes)
			(effects
				(font
					(size 1.016 1.016)
					(thickness 0.1524)
				)
				(justify mirror)
			)
		)
		(duplicate_pad_numbers_are_jumpers no)
		(fp_line
			(start -0.508 -0.9398)
			(end 0.508 -0.9398)
			(stroke
				(width 0.1524)
				(type default)
			)
			(layer "B.SilkS")
		)
		(fp_line
			(start 0.508 -0.9398)
			(end 0.508 0.9398)
			(stroke
				(width 0.1524)
				(type default)
			)
			(layer "B.SilkS")
		)
		(fp_rect
			(start 0.508 0.9398)
			(end -0.508 -0.9398)
			(stroke
				(width 0)
				(type default)
			)
			(fill no)
			(layer "B.CrtYd")
		)
		(fp_rect
			(start 0.508 0.9398)
			(end -0.508 -0.9398)
			(stroke
				(width 0)
				(type default)
			)
			(fill no)
			(layer "B.Fab")
		)
		(pad "1" smd custom
			(at 0 -0.4445 180)
			(size 0.1397 0.1397)
			(layers "B.Cu" "B.Mask" "B.Paste")
			(net "BMC_SSD_RST#0_A14")
			(options
				(clearance outline)
				(anchor circle)
			)
			(primitives
				(gr_poly
					(pts
						(arc
							(start -0.1778 0.2794)
							(mid -0.249642 0.249642)
							(end -0.2794 0.1778)
						)
						(arc
							(start -0.2794 -0.1778)
							(mid -0.249642 -0.249642)
							(end -0.1778 -0.2794)
						)
						(arc
							(start 0.1778 -0.2794)
							(mid 0.249642 -0.249642)
							(end 0.2794 -0.1778)
						)
						(arc
							(start 0.2794 0.1778)
							(mid 0.249642 0.249642)
							(end 0.1778 0.2794)
						)
					)
					(width 0)
					(fill yes)
				)
			)
		)
		(pad "2" smd custom
			(at 0 0.4445 180)
			(size 0.1397 0.1397)
			(layers "B.Cu" "B.Mask" "B.Paste")
			(net "P3V3_STBY")
			(options
				(clearance outline)
				(anchor circle)
			)
			(primitives
				(gr_poly
					(pts
						(arc
							(start -0.1778 0.2794)
							(mid -0.249642 0.249642)
							(end -0.2794 0.1778)
						)
						(arc
							(start -0.2794 -0.1778)
							(mid -0.249642 -0.249642)
							(end -0.1778 -0.2794)
						)
						(arc
							(start 0.1778 -0.2794)
							(mid 0.249642 -0.249642)
							(end 0.2794 -0.1778)
						)
						(arc
							(start 0.2794 0.1778)
							(mid 0.249642 0.249642)
							(end 0.1778 0.2794)
						)
					)
					(width 0)
					(fill yes)
				)
			)
		)
	)
	(footprint ""
		(layer "B.Cu")
		(at 228.6254 -58.996072 90)
		(property "Reference" "C533"
			(at 0 0 90)
			(layer "B.SilkS")
			(hide yes)
			(effects
				(font
					(size 1.27 1.27)
				)
				(justify mirror)
			)
		)
		(property "Value" "SCD1U16V1KX-1-GP"
			(at 2.8321 -1.7399 90)
			(unlocked yes)
			(layer "B.Fab")
			(hide yes)
			(effects
				(font
					(size 1.016 1.016)
					(thickness 0.1524)
				)
				(justify mirror)
			)
		)
		(property "Device Type" "C0201H13"
			(at 2.8321 -3.2639 90)
			(unlocked yes)
			(layer "B.Fab")
			(hide yes)
			(effects
				(font
					(size 1.016 1.016)
					(thickness 0.1524)
				)
				(justify mirror)
			)
		)
		(duplicate_pad_numbers_are_jumpers no)
		(fp_rect
			(start 0.2794 0.6477)
			(end -0.2794 -0.6477)
			(stroke
				(width 0)
				(type default)
			)
			(fill no)
			(layer "B.CrtYd")
		)
		(fp_rect
			(start 0.2794 0.6477)
			(end -0.2794 -0.6477)
			(stroke
				(width 0)
				(type default)
			)
			(fill no)
			(layer "B.Fab")
		)
		(pad "1" smd custom
			(at 0 -0.2794 270)
			(size 0.0762 0.0762)
			(layers "B.Cu" "B.Mask" "B.Paste")
			(net "DUT_AVD_PCIE")
			(options
				(clearance outline)
				(anchor circle)
			)
			(primitives
				(gr_poly
					(pts
						(arc
							(start 0.1524 0.127)
							(mid 0.137521 0.162921)
							(end 0.1016 0.1778)
						)
						(arc
							(start -0.1016 0.1778)
							(mid -0.137521 0.162921)
							(end -0.1524 0.127)
						)
						(arc
							(start -0.1524 -0.127)
							(mid -0.137521 -0.162921)
							(end -0.1016 -0.1778)
						)
						(arc
							(start 0.1016 -0.1778)
							(mid 0.137521 -0.162921)
							(end 0.1524 -0.127)
						)
					)
					(width 0)
					(fill yes)
				)
			)
		)
		(pad "2" smd custom
			(at 0 0.2794 270)
			(size 0.0762 0.0762)
			(layers "B.Cu" "B.Mask" "B.Paste")
			(net "GND")
			(options
				(clearance outline)
				(anchor circle)
			)
			(primitives
				(gr_poly
					(pts
						(arc
							(start 0.1524 0.127)
							(mid 0.137521 0.162921)
							(end 0.1016 0.1778)
						)
						(arc
							(start -0.1016 0.1778)
							(mid -0.137521 0.162921)
							(end -0.1524 0.127)
						)
						(arc
							(start -0.1524 -0.127)
							(mid -0.137521 -0.162921)
							(end -0.1016 -0.1778)
						)
						(arc
							(start 0.1016 -0.1778)
							(mid 0.137521 -0.162921)
							(end 0.1524 -0.127)
						)
					)
					(width 0)
					(fill yes)
				)
			)
		)
	)
	(footprint ""
		(layer "B.Cu")
		(at 225.679 -23.241 180)
		(property "Reference" "R829"
			(at 0 0 0)
			(layer "B.SilkS")
			(hide yes)
			(effects
				(font
					(size 1.27 1.27)
				)
				(justify mirror)
			)
		)
		(property "Value" "0R2J-2-GP"
			(at -0.064008 -3.993896 180)
			(unlocked yes)
			(layer "B.Fab")
			(hide yes)
			(effects
				(font
					(size 1.016 1.016)
					(thickness 0.1524)
				)
				(justify mirror)
			)
		)
		(property "Device Type" "R402H16"
			(at -0.064008 -5.517896 180)
			(unlocked yes)
			(layer "B.Fab")
			(hide yes)
			(effects
				(font
					(size 1.016 1.016)
					(thickness 0.1524)
				)
				(justify mirror)
			)
		)
		(duplicate_pad_numbers_are_jumpers no)
		(fp_line
			(start 0.508 -0.9398)
			(end 0.508 0.9398)
			(stroke
				(width 0.1524)
				(type default)
			)
			(layer "B.SilkS")
		)
		(fp_line
			(start -0.508 -0.9398)
			(end 0.508 -0.9398)
			(stroke
				(width 0.1524)
				(type default)
			)
			(layer "B.SilkS")
		)
		(fp_rect
			(start 0.508 0.9398)
			(end -0.508 -0.9398)
			(stroke
				(width 0)
				(type default)
			)
			(fill no)
			(layer "B.CrtYd")
		)
		(fp_rect
			(start 0.508 0.9398)
			(end -0.508 -0.9398)
			(stroke
				(width 0)
				(type default)
			)
			(fill no)
			(layer "B.Fab")
		)
		(pad "1" smd custom
			(at 0 -0.4445)
			(size 0.1397 0.1397)
			(layers "B.Cu" "B.Mask" "B.Paste")
			(net "HOST5_RST_N_LS")
			(options
				(clearance outline)
				(anchor circle)
			)
			(primitives
				(gr_poly
					(pts
						(arc
							(start -0.1778 0.2794)
							(mid -0.249642 0.249642)
							(end -0.2794 0.1778)
						)
						(arc
							(start -0.2794 -0.1778)
							(mid -0.249642 -0.249642)
							(end -0.1778 -0.2794)
						)
						(arc
							(start 0.1778 -0.2794)
							(mid 0.249642 -0.249642)
							(end 0.2794 -0.1778)
						)
						(arc
							(start 0.2794 0.1778)
							(mid 0.249642 0.249642)
							(end 0.1778 0.2794)
						)
					)
					(width 0)
					(fill yes)
				)
			)
		)
		(pad "2" smd custom
			(at 0 0.4445)
			(size 0.1397 0.1397)
			(layers "B.Cu" "B.Mask" "B.Paste")
			(net "LBI_ADDR_4_R")
			(options
				(clearance outline)
				(anchor circle)
			)
			(primitives
				(gr_poly
					(pts
						(arc
							(start -0.1778 0.2794)
							(mid -0.249642 0.249642)
							(end -0.2794 0.1778)
						)
						(arc
							(start -0.2794 -0.1778)
							(mid -0.249642 -0.249642)
							(end -0.1778 -0.2794)
						)
						(arc
							(start 0.1778 -0.2794)
							(mid 0.249642 -0.249642)
							(end 0.2794 -0.1778)
						)
						(arc
							(start 0.2794 0.1778)
							(mid 0.249642 0.249642)
							(end 0.1778 0.2794)
						)
					)
					(width 0)
					(fill yes)
				)
			)
		)
	)
	(footprint ""
		(layer "B.Cu")
		(at 20.955 -131.699 90)
		(property "Reference" "R359"
			(at 0 0 90)
			(layer "B.SilkS")
			(hide yes)
			(effects
				(font
					(size 1.27 1.27)
				)
				(justify mirror)
			)
		)
		(property "Value" "3K3R2F-2-GP"
			(at -0.064008 -3.993896 90)
			(unlocked yes)
			(layer "B.Fab")
			(hide yes)
			(effects
				(font
					(size 1.016 1.016)
					(thickness 0.1524)
				)
				(justify mirror)
			)
		)
		(property "Device Type" "R402H16"
			(at -0.064008 -5.517896 90)
			(unlocked yes)
			(layer "B.Fab")
			(hide yes)
			(effects
				(font
					(size 1.016 1.016)
					(thickness 0.1524)
				)
				(justify mirror)
			)
		)
		(duplicate_pad_numbers_are_jumpers no)
		(fp_line
			(start 0.508 -0.9398)
			(end 0.508 0.9398)
			(stroke
				(width 0.1524)
				(type default)
			)
			(layer "B.SilkS")
		)
		(fp_line
			(start -0.508 -0.9398)
			(end 0.508 -0.9398)
			(stroke
				(width 0.1524)
				(type default)
			)
			(layer "B.SilkS")
		)
		(fp_rect
			(start 0.508 0.9398)
			(end -0.508 -0.9398)
			(stroke
				(width 0)
				(type default)
			)
			(fill no)
			(layer "B.CrtYd")
		)
		(fp_rect
			(start 0.508 0.9398)
			(end -0.508 -0.9398)
			(stroke
				(width 0)
				(type default)
			)
			(fill no)
			(layer "B.Fab")
		)
		(pad "1" smd custom
			(at 0 -0.4445 270)
			(size 0.1397 0.1397)
			(layers "B.Cu" "B.Mask" "B.Paste")
			(net "P3V3_STBY")
			(options
				(clearance outline)
				(anchor circle)
			)
			(primitives
				(gr_poly
					(pts
						(arc
							(start -0.1778 0.2794)
							(mid -0.249642 0.249642)
							(end -0.2794 0.1778)
						)
						(arc
							(start -0.2794 -0.1778)
							(mid -0.249642 -0.249642)
							(end -0.1778 -0.2794)
						)
						(arc
							(start 0.1778 -0.2794)
							(mid 0.249642 -0.249642)
							(end 0.2794 -0.1778)
						)
						(arc
							(start 0.2794 0.1778)
							(mid 0.249642 0.249642)
							(end 0.1778 0.2794)
						)
					)
					(width 0)
					(fill yes)
				)
			)
		)
		(pad "2" smd custom
			(at 0 0.4445 270)
			(size 0.1397 0.1397)
			(layers "B.Cu" "B.Mask" "B.Paste")
			(net "ROMA5")
			(options
				(clearance outline)
				(anchor circle)
			)
			(primitives
				(gr_poly
					(pts
						(arc
							(start -0.1778 0.2794)
							(mid -0.249642 0.249642)
							(end -0.2794 0.1778)
						)
						(arc
							(start -0.2794 -0.1778)
							(mid -0.249642 -0.249642)
							(end -0.1778 -0.2794)
						)
						(arc
							(start 0.1778 -0.2794)
							(mid 0.249642 -0.249642)
							(end 0.2794 -0.1778)
						)
						(arc
							(start 0.2794 0.1778)
							(mid 0.249642 0.249642)
							(end 0.1778 0.2794)
						)
					)
					(width 0)
					(fill yes)
				)
			)
		)
	)
)
